(kicad_pcb
	(version 20221018)
	(generator pcbnew)
	(general
    (thickness 1.7403)
  )
	(paper "A4")
	(title_block
    (title "Data Center RDIMM DDR4 Tester")
    (date "2024-09-30")
    (rev "1.2.4")
		(comment 9 "footprint 571 of 690 (J5), pads 1-109 of 404")
	)
	(layers
    (0 "F.Cu" signal)
    (1 "In1.Cu" power)
    (2 "In2.Cu" signal)
    (3 "In3.Cu" power)
    (4 "In4.Cu" power)
    (5 "In5.Cu" signal)
    (6 "In6.Cu" power)
    (7 "In7.Cu" signal)
    (8 "In8.Cu" power)
    (9 "In9.Cu" signal)
    (10 "In10.Cu" power)
    (31 "B.Cu" signal)
    (32 "B.Adhes" user "B.Adhesive")
    (33 "F.Adhes" user "F.Adhesive")
    (34 "B.Paste" user)
    (35 "F.Paste" user)
    (36 "B.SilkS" user "B.Silkscreen")
    (37 "F.SilkS" user "F.Silkscreen")
    (38 "B.Mask" user)
    (39 "F.Mask" user)
    (40 "Dwgs.User" user "User.Drawings")
    (41 "Cmts.User" user "User.Comments")
    (42 "Eco1.User" user "User.Eco1")
    (43 "Eco2.User" user "User.Eco2")
    (44 "Edge.Cuts" user)
    (45 "Margin" user)
    (46 "B.CrtYd" user "B.Courtyard")
    (47 "F.CrtYd" user "F.Courtyard")
    (48 "B.Fab" user)
    (49 "F.Fab" user)
  )
	(footprint "data-center-rdimm-ddr4-tester-footprints:FMC_SAMTEC_ASP-134486-01"
    (layer "B.Cu")
    (at 251 100 90)
    (descr "VITA 57.1 FMC – SEARAY™ HPC")
    (property "Author" "Antmicro")
    (property "License" "Apache-2.0")
    (property "MPN" "ASP-134486-01")
    (property "Manufacturer" "Samtec")
    (property "Sheetfile" "fmc_hpc.kicad_sch")
    (property "Sheetname" "FMC HPC")
    (property "ki_description" "400-pole 10-row 1.27mm Female FMC HPC Connector with gold-plated copper alloy contacts. ")
    (attr smd)
    (fp_text reference "J5" (at -28.4 4.01 270) (layer "B.SilkS")
        (effects (font (size 0.7 0.7) (thickness 0.15)) (justify left bottom mirror))
    )
    (fp_text value "ASP-134486-01" (at 0 -7.9 270) (layer "B.Fab") hide
        (effects (font (size 0.7 0.7) (thickness 0.15)) (justify left bottom mirror))
    )
    (pad "" np_thru_hole circle (at -31.499 -1.999 270) (size 6 6) (drill 3.2) (layers "*.Cu" "*.Mask"))
    (pad "" np_thru_hole circle (at -27.189 3.05 270) (size 1.27 1.27) (drill 1.27) (layers "F&B.Cu" "*.Mask"))
    (pad "" np_thru_hole circle (at 27.19 0 90) (size 1.27 1.27) (drill 1.27) (layers "*.Cu" "*.Mask"))
    (pad "" np_thru_hole circle (at 31.501 -1.999 270) (size 6 6) (drill 3.2) (layers "*.Cu" "*.Mask"))
    (pad "A1" smd circle (at -24.766 5.715 270) (size 0.64 0.64) (layers "B.Cu" "B.Mask")
      (net 9 "GND") (pinfunction "GND") (pintype "passive"))
    (pad "A2" smd circle (at -23.496 5.715 270) (size 0.64 0.64) (layers "B.Cu" "B.Mask")
      (net 632 "GTX_RX1_P") (pinfunction "DP1_{M2C}+") (pintype "passive"))
    (pad "A3" smd circle (at -22.226 5.715 270) (size 0.64 0.64) (layers "B.Cu" "B.Mask")
      (net 633 "GTX_RX1_N") (pinfunction "DP1_{M2C}-") (pintype "passive"))
    (pad "A4" smd circle (at -20.955 5.715 270) (size 0.64 0.64) (layers "B.Cu" "B.Mask")
      (net 9 "GND") (pinfunction "GND") (pintype "passive"))
    (pad "A5" smd circle (at -19.685 5.715 270) (size 0.64 0.64) (layers "B.Cu" "B.Mask")
      (net 9 "GND") (pinfunction "GND") (pintype "passive"))
    (pad "A6" smd circle (at -18.415 5.715 270) (size 0.64 0.64) (layers "B.Cu" "B.Mask")
      (net 634 "GTX_RX2_P") (pinfunction "DP2_{M2C}+") (pintype "passive"))
    (pad "A7" smd circle (at -17.145 5.715 270) (size 0.64 0.64) (layers "B.Cu" "B.Mask")
      (net 635 "GTX_RX2_N") (pinfunction "DP2_{M2C}-") (pintype "passive"))
    (pad "A8" smd circle (at -15.875 5.715 270) (size 0.64 0.64) (layers "B.Cu" "B.Mask")
      (net 9 "GND") (pinfunction "GND") (pintype "passive"))
    (pad "A9" smd circle (at -14.606 5.715 270) (size 0.64 0.64) (layers "B.Cu" "B.Mask")
      (net 9 "GND") (pinfunction "GND") (pintype "passive"))
    (pad "A10" smd circle (at -13.336 5.715 270) (size 0.64 0.64) (layers "B.Cu" "B.Mask")
      (net 636 "GTX_RX3_P") (pinfunction "DP3_{M2C}+") (pintype "passive"))
    (pad "A11" smd circle (at -12.065 5.715 270) (size 0.64 0.64) (layers "B.Cu" "B.Mask")
      (net 637 "GTX_RX3_N") (pinfunction "DP3_{M2C}-") (pintype "passive"))
    (pad "A12" smd circle (at -10.795 5.715 270) (size 0.64 0.64) (layers "B.Cu" "B.Mask")
      (net 9 "GND") (pinfunction "GND") (pintype "passive"))
    (pad "A13" smd circle (at -9.526 5.715 270) (size 0.64 0.64) (layers "B.Cu" "B.Mask")
      (net 9 "GND") (pinfunction "GND") (pintype "passive"))
    (pad "A14" smd circle (at -8.256 5.715 270) (size 0.64 0.64) (layers "B.Cu" "B.Mask")
      (net 638 "GTX_RX4_P") (pinfunction "DP4_{M2C}+") (pintype "passive"))
    (pad "A15" smd circle (at -6.986 5.715 270) (size 0.64 0.64) (layers "B.Cu" "B.Mask")
      (net 639 "GTX_RX4_N") (pinfunction "DP4_{M2C}-") (pintype "passive"))
    (pad "A16" smd circle (at -5.715 5.715 270) (size 0.64 0.64) (layers "B.Cu" "B.Mask")
      (net 9 "GND") (pinfunction "GND") (pintype "passive"))
    (pad "A17" smd circle (at -4.446 5.715 270) (size 0.64 0.64) (layers "B.Cu" "B.Mask")
      (net 9 "GND") (pinfunction "GND") (pintype "passive"))
    (pad "A18" smd circle (at -3.175 5.715 270) (size 0.64 0.64) (layers "B.Cu" "B.Mask")
      (net 640 "GTX_RX5_P") (pinfunction "DP5_{M2C}+") (pintype "passive"))
    (pad "A19" smd circle (at -1.905 5.715 270) (size 0.64 0.64) (layers "B.Cu" "B.Mask")
      (net 641 "GTX_RX5_N") (pinfunction "DP5_{M2C}-") (pintype "passive"))
    (pad "A20" smd circle (at -0.635 5.715 270) (size 0.64 0.64) (layers "B.Cu" "B.Mask")
      (net 9 "GND") (pinfunction "GND") (pintype "passive"))
    (pad "A21" smd circle (at 0.634 5.715 270) (size 0.64 0.64) (layers "B.Cu" "B.Mask")
      (net 9 "GND") (pinfunction "GND") (pintype "passive"))
    (pad "A22" smd circle (at 1.904 5.715 270) (size 0.64 0.64) (layers "B.Cu" "B.Mask")
      (net 419 "/FMC HPC/GTX_TX1_C_P") (pinfunction "DP1_{C2M}+") (pintype "passive"))
    (pad "A23" smd circle (at 3.174 5.715 270) (size 0.64 0.64) (layers "B.Cu" "B.Mask")
      (net 421 "/FMC HPC/GTX_TX1_C_N") (pinfunction "DP1_{C2M}-") (pintype "passive"))
    (pad "A24" smd circle (at 4.445 5.715 270) (size 0.64 0.64) (layers "B.Cu" "B.Mask")
      (net 9 "GND") (pinfunction "GND") (pintype "passive"))
    (pad "A25" smd circle (at 5.714 5.715 270) (size 0.64 0.64) (layers "B.Cu" "B.Mask")
      (net 9 "GND") (pinfunction "GND") (pintype "passive"))
    (pad "A26" smd circle (at 6.985 5.715 270) (size 0.64 0.64) (layers "B.Cu" "B.Mask")
      (net 430 "/FMC HPC/GTX_TX2_C_P") (pinfunction "DP2_{C2M}+") (pintype "passive"))
    (pad "A27" smd circle (at 8.255 5.715 270) (size 0.64 0.64) (layers "B.Cu" "B.Mask")
      (net 438 "/FMC HPC/GTX_TX2_C_N") (pinfunction "DP2_{C2M}-") (pintype "passive"))
    (pad "A28" smd circle (at 9.525 5.715 270) (size 0.64 0.64) (layers "B.Cu" "B.Mask")
      (net 9 "GND") (pinfunction "GND") (pintype "passive"))
    (pad "A29" smd circle (at 10.794 5.715 270) (size 0.64 0.64) (layers "B.Cu" "B.Mask")
      (net 9 "GND") (pinfunction "GND") (pintype "passive"))
    (pad "A30" smd circle (at 12.064 5.715 270) (size 0.64 0.64) (layers "B.Cu" "B.Mask")
      (net 440 "/FMC HPC/GTX_TX3_C_P") (pinfunction "DP3_{C2M}+") (pintype "passive"))
    (pad "A31" smd circle (at 13.335 5.715 270) (size 0.64 0.64) (layers "B.Cu" "B.Mask")
      (net 451 "/FMC HPC/GTX_TX3_C_N") (pinfunction "DP3_{C2M}-") (pintype "passive"))
    (pad "A32" smd circle (at 14.605 5.715 270) (size 0.64 0.64) (layers "B.Cu" "B.Mask")
      (net 9 "GND") (pinfunction "GND") (pintype "passive"))
    (pad "A33" smd circle (at 15.874 5.715 270) (size 0.64 0.64) (layers "B.Cu" "B.Mask")
      (net 9 "GND") (pinfunction "GND") (pintype "passive"))
    (pad "A34" smd circle (at 17.144 5.715 270) (size 0.64 0.64) (layers "B.Cu" "B.Mask")
      (net 464 "/FMC HPC/GTX_TX4_C_P") (pinfunction "DP4_{C2M}+") (pintype "passive"))
    (pad "A35" smd circle (at 18.414 5.715 270) (size 0.64 0.64) (layers "B.Cu" "B.Mask")
      (net 466 "/FMC HPC/GTX_TX4_C_N") (pinfunction "DP4_{C2M}-") (pintype "passive"))
    (pad "A36" smd circle (at 19.684 5.715 270) (size 0.64 0.64) (layers "B.Cu" "B.Mask")
      (net 9 "GND") (pinfunction "GND") (pintype "passive"))
    (pad "A37" smd circle (at 20.954 5.715 270) (size 0.64 0.64) (layers "B.Cu" "B.Mask")
      (net 9 "GND") (pinfunction "GND") (pintype "passive"))
    (pad "A38" smd circle (at 22.225 5.715 270) (size 0.64 0.64) (layers "B.Cu" "B.Mask")
      (net 480 "/FMC HPC/GTX_TX5_C_P") (pinfunction "DP5_{C2M}+") (pintype "passive"))
    (pad "A39" smd circle (at 23.495 5.715 270) (size 0.64 0.64) (layers "B.Cu" "B.Mask")
      (net 482 "/FMC HPC/GTX_TX5_C_N") (pinfunction "DP5_{C2M}-") (pintype "passive"))
    (pad "A40" smd circle (at 24.765 5.715 270) (size 0.64 0.64) (layers "B.Cu" "B.Mask")
      (net 9 "GND") (pinfunction "GND") (pintype "passive"))
    (pad "B1" smd circle (at -24.766 4.446 270) (size 0.64 0.64) (layers "B.Cu" "B.Mask")
      (net 449 "CLK_DIR") (pinfunction "CLK_{DIR}") (pintype "passive"))
    (pad "B2" smd circle (at -23.496 4.446 270) (size 0.64 0.64) (layers "B.Cu" "B.Mask")
      (net 9 "GND") (pinfunction "GND") (pintype "passive"))
    (pad "B3" smd circle (at -22.226 4.446 270) (size 0.64 0.64) (layers "B.Cu" "B.Mask")
      (net 9 "GND") (pinfunction "GND") (pintype "passive"))
    (pad "B4" smd circle (at -20.955 4.446 270) (size 0.64 0.64) (layers "B.Cu" "B.Mask")
      (net 114 "unconnected-(J5E-DP9_{M2C}+-PadB4)") (pinfunction "DP9_{M2C}+") (pintype "passive+no_connect"))
    (pad "B5" smd circle (at -19.685 4.446 270) (size 0.64 0.64) (layers "B.Cu" "B.Mask")
      (net 116 "unconnected-(J5E-DP9_{M2C}--PadB5)") (pinfunction "DP9_{M2C}-") (pintype "passive+no_connect"))
    (pad "B6" smd circle (at -18.415 4.446 270) (size 0.64 0.64) (layers "B.Cu" "B.Mask")
      (net 9 "GND") (pinfunction "GND") (pintype "passive"))
    (pad "B7" smd circle (at -17.145 4.446 270) (size 0.64 0.64) (layers "B.Cu" "B.Mask")
      (net 9 "GND") (pinfunction "GND") (pintype "passive"))
    (pad "B8" smd circle (at -15.875 4.446 270) (size 0.64 0.64) (layers "B.Cu" "B.Mask")
      (net 117 "unconnected-(J5E-DP8_{M2C}+-PadB8)") (pinfunction "DP8_{M2C}+") (pintype "passive+no_connect"))
    (pad "B9" smd circle (at -14.606 4.446 270) (size 0.64 0.64) (layers "B.Cu" "B.Mask")
      (net 121 "unconnected-(J5E-DP8_{M2C}--PadB9)") (pinfunction "DP8_{M2C}-") (pintype "passive+no_connect"))
    (pad "B10" smd circle (at -13.336 4.446 270) (size 0.64 0.64) (layers "B.Cu" "B.Mask")
      (net 9 "GND") (pinfunction "GND") (pintype "passive"))
    (pad "B11" smd circle (at -12.065 4.446 270) (size 0.64 0.64) (layers "B.Cu" "B.Mask")
      (net 9 "GND") (pinfunction "GND") (pintype "passive"))
    (pad "B12" smd circle (at -10.795 4.446 270) (size 0.64 0.64) (layers "B.Cu" "B.Mask")
      (net 645 "GTX_RX7_P") (pinfunction "DP7_{M2C}+") (pintype "passive"))
    (pad "B13" smd circle (at -9.526 4.446 270) (size 0.64 0.64) (layers "B.Cu" "B.Mask")
      (net 646 "GTX_RX7_N") (pinfunction "DP7_{M2C}-") (pintype "passive"))
    (pad "B14" smd circle (at -8.256 4.446 270) (size 0.64 0.64) (layers "B.Cu" "B.Mask")
      (net 9 "GND") (pinfunction "GND") (pintype "passive"))
    (pad "B15" smd circle (at -6.986 4.446 270) (size 0.64 0.64) (layers "B.Cu" "B.Mask")
      (net 9 "GND") (pinfunction "GND") (pintype "passive"))
    (pad "B16" smd circle (at -5.715 4.446 270) (size 0.64 0.64) (layers "B.Cu" "B.Mask")
      (net 647 "GTX_RX6_P") (pinfunction "DP6_{M2C}+") (pintype "passive"))
    (pad "B17" smd circle (at -4.446 4.446 270) (size 0.64 0.64) (layers "B.Cu" "B.Mask")
      (net 648 "GTX_RX6_N") (pinfunction "DP6_{M2C}-") (pintype "passive"))
    (pad "B18" smd circle (at -3.175 4.446 270) (size 0.64 0.64) (layers "B.Cu" "B.Mask")
      (net 9 "GND") (pinfunction "GND") (pintype "passive"))
    (pad "B19" smd circle (at -1.905 4.446 270) (size 0.64 0.64) (layers "B.Cu" "B.Mask")
      (net 9 "GND") (pinfunction "GND") (pintype "passive"))
    (pad "B20" smd circle (at -0.635 4.446 270) (size 0.64 0.64) (layers "B.Cu" "B.Mask")
      (net 897 "/FMC HPC/GTR_REFCLK1_R_P") (pinfunction "GBTCLK1_{M2C}+") (pintype "passive"))
    (pad "B21" smd circle (at 0.634 4.446 270) (size 0.64 0.64) (layers "B.Cu" "B.Mask")
      (net 898 "/FMC HPC/GTR_REFCLK1_R_N") (pinfunction "GBTCLK1_{M2C}-") (pintype "passive"))
    (pad "B22" smd circle (at 1.904 4.446 270) (size 0.64 0.64) (layers "B.Cu" "B.Mask")
      (net 9 "GND") (pinfunction "GND") (pintype "passive"))
    (pad "B23" smd circle (at 3.174 4.446 270) (size 0.64 0.64) (layers "B.Cu" "B.Mask")
      (net 9 "GND") (pinfunction "GND") (pintype "passive"))
    (pad "B24" smd circle (at 4.445 4.446 270) (size 0.64 0.64) (layers "B.Cu" "B.Mask")
      (net 122 "unconnected-(J5E-DP9_{C2M}+-PadB24)") (pinfunction "DP9_{C2M}+") (pintype "passive+no_connect"))
    (pad "B25" smd circle (at 5.714 4.446 270) (size 0.64 0.64) (layers "B.Cu" "B.Mask")
      (net 123 "unconnected-(J5E-DP9_{C2M}--PadB25)") (pinfunction "DP9_{C2M}-") (pintype "passive+no_connect"))
    (pad "B26" smd circle (at 6.985 4.446 270) (size 0.64 0.64) (layers "B.Cu" "B.Mask")
      (net 9 "GND") (pinfunction "GND") (pintype "passive"))
    (pad "B27" smd circle (at 8.255 4.446 270) (size 0.64 0.64) (layers "B.Cu" "B.Mask")
      (net 9 "GND") (pinfunction "GND") (pintype "passive"))
    (pad "B28" smd circle (at 9.525 4.446 270) (size 0.64 0.64) (layers "B.Cu" "B.Mask")
      (net 124 "unconnected-(J5E-DP8_{C2M}+-PadB28)") (pinfunction "DP8_{C2M}+") (pintype "passive+no_connect"))
    (pad "B29" smd circle (at 10.794 4.446 270) (size 0.64 0.64) (layers "B.Cu" "B.Mask")
      (net 125 "unconnected-(J5E-DP8_{C2M}--PadB29)") (pinfunction "DP8_{C2M}-") (pintype "passive+no_connect"))
    (pad "B30" smd circle (at 12.064 4.446 270) (size 0.64 0.64) (layers "B.Cu" "B.Mask")
      (net 9 "GND") (pinfunction "GND") (pintype "passive"))
    (pad "B31" smd circle (at 13.335 4.446 270) (size 0.64 0.64) (layers "B.Cu" "B.Mask")
      (net 9 "GND") (pinfunction "GND") (pintype "passive"))
    (pad "B32" smd circle (at 14.605 4.446 270) (size 0.64 0.64) (layers "B.Cu" "B.Mask")
      (net 513 "/FMC HPC/GTX_TX7_C_P") (pinfunction "DP7_{C2M}+") (pintype "passive"))
    (pad "B33" smd circle (at 15.874 4.446 270) (size 0.64 0.64) (layers "B.Cu" "B.Mask")
      (net 525 "/FMC HPC/GTX_TX7_C_N") (pinfunction "DP7_{C2M}-") (pintype "passive"))
    (pad "B34" smd circle (at 17.144 4.446 270) (size 0.64 0.64) (layers "B.Cu" "B.Mask")
      (net 9 "GND") (pinfunction "GND") (pintype "passive"))
    (pad "B35" smd circle (at 18.414 4.446 270) (size 0.64 0.64) (layers "B.Cu" "B.Mask")
      (net 9 "GND") (pinfunction "GND") (pintype "passive"))
    (pad "B36" smd circle (at 19.684 4.446 270) (size 0.64 0.64) (layers "B.Cu" "B.Mask")
      (net 497 "/FMC HPC/GTX_TX6_C_P") (pinfunction "DP6_{C2M}+") (pintype "passive"))
    (pad "B37" smd circle (at 20.954 4.446 270) (size 0.64 0.64) (layers "B.Cu" "B.Mask")
      (net 499 "/FMC HPC/GTX_TX6_C_N") (pinfunction "DP6_{C2M}-") (pintype "passive"))
    (pad "B38" smd circle (at 22.225 4.446 270) (size 0.64 0.64) (layers "B.Cu" "B.Mask")
      (net 9 "GND") (pinfunction "GND") (pintype "passive"))
    (pad "B39" smd circle (at 23.495 4.446 270) (size 0.64 0.64) (layers "B.Cu" "B.Mask")
      (net 9 "GND") (pinfunction "GND") (pintype "passive"))
    (pad "B40" smd circle (at 24.765 4.446 270) (size 0.64 0.64) (layers "B.Cu" "B.Mask")
      (net 127 "unconnected-(J5E-RES0-PadB40)") (pinfunction "RES0") (pintype "passive+no_connect"))
    (pad "C1" smd circle (at -24.766 3.175 270) (size 0.64 0.64) (layers "B.Cu" "B.Mask")
      (net 9 "GND") (pinfunction "GND") (pintype "passive"))
    (pad "C2" smd circle (at -23.496 3.175 270) (size 0.64 0.64) (layers "B.Cu" "B.Mask")
      (net 410 "/FMC HPC/GTX_TX0_C_P") (pinfunction "DP0_{C2M}+") (pintype "passive"))
    (pad "C3" smd circle (at -22.226 3.175 270) (size 0.64 0.64) (layers "B.Cu" "B.Mask")
      (net 412 "/FMC HPC/GTX_TX0_C_N") (pinfunction "DP0_{C2M}-") (pintype "passive"))
    (pad "C4" smd circle (at -20.955 3.175 270) (size 0.64 0.64) (layers "B.Cu" "B.Mask")
      (net 9 "GND") (pinfunction "GND") (pintype "passive"))
    (pad "C5" smd circle (at -19.685 3.175 270) (size 0.64 0.64) (layers "B.Cu" "B.Mask")
      (net 9 "GND") (pinfunction "GND") (pintype "passive"))
    (pad "C6" smd circle (at -18.415 3.175 270) (size 0.64 0.64) (layers "B.Cu" "B.Mask")
      (net 655 "GTX_RX0_P") (pinfunction "DP0_{M2C}+") (pintype "passive"))
    (pad "C7" smd circle (at -17.145 3.175 270) (size 0.64 0.64) (layers "B.Cu" "B.Mask")
      (net 656 "GTX_RX0_N") (pinfunction "DP0_{M2C}-") (pintype "passive"))
    (pad "C8" smd circle (at -15.875 3.175 270) (size 0.64 0.64) (layers "B.Cu" "B.Mask")
      (net 9 "GND") (pinfunction "GND") (pintype "passive"))
    (pad "C9" smd circle (at -14.606 3.175 270) (size 0.64 0.64) (layers "B.Cu" "B.Mask")
      (net 9 "GND") (pinfunction "GND") (pintype "passive"))
    (pad "C10" smd circle (at -13.336 3.175 270) (size 0.64 0.64) (layers "B.Cu" "B.Mask")
      (net 129 "unconnected-(J5D-LA06+-PadC10)") (pinfunction "LA06+") (pintype "passive+no_connect"))
    (pad "C11" smd circle (at -12.065 3.175 270) (size 0.64 0.64) (layers "B.Cu" "B.Mask")
      (net 130 "unconnected-(J5D-LA06--PadC11)") (pinfunction "LA06-") (pintype "passive+no_connect"))
    (pad "C12" smd circle (at -10.795 3.175 270) (size 0.64 0.64) (layers "B.Cu" "B.Mask")
      (net 9 "GND") (pinfunction "GND") (pintype "passive"))
    (pad "C13" smd circle (at -9.526 3.175 270) (size 0.64 0.64) (layers "B.Cu" "B.Mask")
      (net 9 "GND") (pinfunction "GND") (pintype "passive"))
    (pad "C14" smd circle (at -8.256 3.175 270) (size 0.64 0.64) (layers "B.Cu" "B.Mask")
      (net 132 "unconnected-(J5D-LA10+-PadC14)") (pinfunction "LA10+") (pintype "passive+no_connect"))
    (pad "C15" smd circle (at -6.986 3.175 270) (size 0.64 0.64) (layers "B.Cu" "B.Mask")
      (net 134 "unconnected-(J5D-LA10--PadC15)") (pinfunction "LA10-") (pintype "passive+no_connect"))
    (pad "C16" smd circle (at -5.715 3.175 270) (size 0.64 0.64) (layers "B.Cu" "B.Mask")
      (net 9 "GND") (pinfunction "GND") (pintype "passive"))
    (pad "C17" smd circle (at -4.446 3.175 270) (size 0.64 0.64) (layers "B.Cu" "B.Mask")
      (net 9 "GND") (pinfunction "GND") (pintype "passive"))
    (pad "C18" smd circle (at -3.175 3.175 270) (size 0.64 0.64) (layers "B.Cu" "B.Mask")
      (net 136 "unconnected-(J5D-LA14+-PadC18)") (pinfunction "LA14+") (pintype "passive+no_connect"))
    (pad "C19" smd circle (at -1.905 3.175 270) (size 0.64 0.64) (layers "B.Cu" "B.Mask")
      (net 138 "unconnected-(J5D-LA14--PadC19)") (pinfunction "LA14-") (pintype "passive+no_connect"))
    (pad "C20" smd circle (at -0.635 3.175 270) (size 0.64 0.64) (layers "B.Cu" "B.Mask")
      (net 9 "GND") (pinfunction "GND") (pintype "passive"))
    (pad "C21" smd circle (at 0.634 3.175 270) (size 0.64 0.64) (layers "B.Cu" "B.Mask")
      (net 9 "GND") (pinfunction "GND") (pintype "passive"))
    (pad "C22" smd circle (at 1.904 3.175 270) (size 0.64 0.64) (layers "B.Cu" "B.Mask")
      (net 140 "unconnected-(J5D-LA18_{CC}+-PadC22)") (pinfunction "LA18_{CC}+") (pintype "passive+no_connect"))
    (pad "C23" smd circle (at 3.174 3.175 270) (size 0.64 0.64) (layers "B.Cu" "B.Mask")
      (net 142 "unconnected-(J5D-LA18_{CC}--PadC23)") (pinfunction "LA18_{CC}-") (pintype "passive+no_connect"))
    (pad "C24" smd circle (at 4.445 3.175 270) (size 0.64 0.64) (layers "B.Cu" "B.Mask")
      (net 9 "GND") (pinfunction "GND") (pintype "passive"))
    (pad "C25" smd circle (at 5.714 3.175 270) (size 0.64 0.64) (layers "B.Cu" "B.Mask")
      (net 9 "GND") (pinfunction "GND") (pintype "passive"))
  )
)
